(kicad_pcb
	(version 20260206)
	(generator "pcbnew")
	(generator_version "10.0")
	(general
		(thickness 1.6)
		(legacy_teardrops no)
	)
	(paper "A4")
	(title_block
		(title "v1-pdb — T6M_PDB_D_0927_0900.brd")
		(comment 1 "Open CloudServer (Microsoft) / footprint 307 of 321 (J11), pads 1-46 of 46")
	)
	(layers
		(0 "F.Cu" signal "TOP")
		(4 "In1.Cu" signal "GND")
		(6 "In2.Cu" signal "IN1")
		(8 "In3.Cu" signal "VCC")
		(10 "In4.Cu" signal "VCC1")
		(12 "In5.Cu" signal "IN2")
		(14 "In6.Cu" signal "GND1")
		(2 "B.Cu" signal "BOTTOM")
		(9 "F.Adhes" user "F.Adhesive")
		(11 "B.Adhes" user "B.Adhesive")
		(13 "F.Paste" user "Package Geometry/Pastemask Top")
		(15 "B.Paste" user "Package Geometry/Pastemask Bottom")
		(5 "F.SilkS" user "Ref Des/Silkscreen Top")
		(7 "B.SilkS" user "Ref Des/Silkscreen Bottom")
		(1 "F.Mask" user "Board Geometry/Soldermask Top")
		(3 "B.Mask" user "Board Geometry/Soldermask Bottom")
		(17 "Dwgs.User" user "User.Drawings")
		(19 "Cmts.User" user "User.Comments")
		(21 "Eco1.User" user "User.Eco1")
		(23 "Eco2.User" user "User.Eco2")
		(25 "Edge.Cuts" user "Board Geometry/Outline")
		(27 "Margin" user)
		(31 "F.CrtYd" user "Package Geometry/Place Bound Top")
		(29 "B.CrtYd" user "Package Geometry/Place Bound Bottom")
		(35 "F.Fab" user "Ref Des/Assembly Top")
		(33 "B.Fab" user "Ref Des/Assembly Bottom")
	)
	(footprint ""
		(layer "B.Cu")
		(at 44.040044 -186.06008 90)
		(property "Reference" "J11"
			(at 6.252972 -4.579366 0)
			(unlocked yes)
			(layer "B.SilkS")
			(effects
				(font
					(size 0.7874 0.5842)
					(thickness 0.1524)
				)
				(justify left mirror)
			)
		)
		(property "Value" ""
			(at 0 0 90)
			(layer "B.Fab")
			(effects
				(font
					(size 1.27 1.27)
				)
				(justify mirror)
			)
		)
		(duplicate_pad_numbers_are_jumpers no)
		(pad "" np_thru_hole circle
			(at -1.35001 -2.54)
			(size 2.5146 2.5146)
			(drill 2.5146)
			(layers "*.Cu" "*.Mask")
			(clearance 0.381)
			(thermal_gap 0.381)
		)
		(pad "" np_thru_hole circle
			(at 0 50.8)
			(size 2.5146 2.5146)
			(drill 2.5146)
			(layers "*.Cu" "*.Mask")
			(clearance 0.381)
			(thermal_gap 0.381)
		)
		(pad "P1" thru_hole rect
			(at 0 0)
			(size 1.1684 1.1684)
			(drill 0.762)
			(layers "*.Cu" "*.Mask")
			(remove_unused_layers no)
			(net "GND")
			(clearance 0.0508)
			(padstack
				(mode front_inner_back)
				(layer "Inner"
					(shape circle)
					(size 1.1684 1.1684)
					(clearance 0.0508)
				)
				(layer "B.Cu"
					(shape rect)
					(size 1.1684 1.1684)
					(thermal_gap 0.0508)
					(clearance 0.0508)
				)
			)
		)
		(pad "P2" thru_hole circle
			(at 0 2.54)
			(size 1.1684 1.1684)
			(drill 0.762)
			(layers "*.Cu" "*.Mask")
			(remove_unused_layers no)
			(net "GND")
			(clearance 0.0508)
			(thermal_gap 0.0508)
		)
		(pad "P3" thru_hole circle
			(at 0 5.08)
			(size 1.1684 1.1684)
			(drill 0.762)
			(layers "*.Cu" "*.Mask")
			(remove_unused_layers no)
			(net "GND")
			(clearance 0.0508)
			(thermal_gap 0.0508)
		)
		(pad "P4" thru_hole circle
			(at 0 7.62)
			(size 1.1684 1.1684)
			(drill 0.762)
			(layers "*.Cu" "*.Mask")
			(remove_unused_layers no)
			(net "GND")
			(clearance 0.0508)
			(thermal_gap 0.0508)
		)
		(pad "P5" thru_hole circle
			(at 0 10.16)
			(size 1.1684 1.1684)
			(drill 0.762)
			(layers "*.Cu" "*.Mask")
			(remove_unused_layers no)
			(net "GND")
			(clearance 0.0508)
			(thermal_gap 0.0508)
		)
		(pad "P6" thru_hole circle
			(at 0 12.7)
			(size 1.1684 1.1684)
			(drill 0.762)
			(layers "*.Cu" "*.Mask")
			(remove_unused_layers no)
			(net "GND")
			(clearance 0.0508)
			(thermal_gap 0.0508)
		)
		(pad "P7" thru_hole circle
			(at 0 15.24)
			(size 1.1684 1.1684)
			(drill 0.762)
			(layers "*.Cu" "*.Mask")
			(remove_unused_layers no)
			(net "GND")
			(clearance 0.0508)
			(thermal_gap 0.0508)
		)
		(pad "P8" thru_hole circle
			(at 0 17.78)
			(size 1.1684 1.1684)
			(drill 0.762)
			(layers "*.Cu" "*.Mask")
			(remove_unused_layers no)
			(net "GND")
			(clearance 0.0508)
			(thermal_gap 0.0508)
		)
		(pad "P9" thru_hole circle
			(at 0 20.32)
			(size 1.1684 1.1684)
			(drill 0.762)
			(layers "*.Cu" "*.Mask")
			(remove_unused_layers no)
			(net "P12V")
			(clearance 0.0508)
			(thermal_gap 0.0508)
		)
		(pad "P10" thru_hole circle
			(at 0 22.86)
			(size 1.1684 1.1684)
			(drill 0.762)
			(layers "*.Cu" "*.Mask")
			(remove_unused_layers no)
			(net "P12V")
			(clearance 0.0508)
			(thermal_gap 0.0508)
		)
		(pad "P11" thru_hole circle
			(at 0 25.4)
			(size 1.1684 1.1684)
			(drill 0.762)
			(layers "*.Cu" "*.Mask")
			(remove_unused_layers no)
			(net "P12V")
			(clearance 0.0508)
			(thermal_gap 0.0508)
		)
		(pad "P12" thru_hole circle
			(at 0 27.94)
			(size 1.1684 1.1684)
			(drill 0.762)
			(layers "*.Cu" "*.Mask")
			(remove_unused_layers no)
			(net "P12V")
			(clearance 0.0508)
			(thermal_gap 0.0508)
		)
		(pad "P13" thru_hole circle
			(at 0 30.48)
			(size 1.1684 1.1684)
			(drill 0.762)
			(layers "*.Cu" "*.Mask")
			(remove_unused_layers no)
			(net "P12V")
			(clearance 0.0508)
			(thermal_gap 0.0508)
		)
		(pad "P14" thru_hole circle
			(at 0 33.02)
			(size 1.1684 1.1684)
			(drill 0.762)
			(layers "*.Cu" "*.Mask")
			(remove_unused_layers no)
			(net "P12V")
			(clearance 0.0508)
			(thermal_gap 0.0508)
		)
		(pad "P15" thru_hole circle
			(at 0 35.56)
			(size 1.1684 1.1684)
			(drill 0.762)
			(layers "*.Cu" "*.Mask")
			(remove_unused_layers no)
			(net "P12V")
			(clearance 0.0508)
			(thermal_gap 0.0508)
		)
		(pad "P16" thru_hole circle
			(at 0 38.1)
			(size 1.1684 1.1684)
			(drill 0.762)
			(layers "*.Cu" "*.Mask")
			(remove_unused_layers no)
			(net "P12V")
			(clearance 0.0508)
			(thermal_gap 0.0508)
		)
		(pad "P17" thru_hole circle
			(at -2.70002 38.1)
			(size 1.1684 1.1684)
			(drill 0.762)
			(layers "*.Cu" "*.Mask")
			(remove_unused_layers no)
			(net "P12V")
			(clearance 0.0508)
			(thermal_gap 0.0508)
		)
		(pad "P18" thru_hole circle
			(at -2.70002 35.56)
			(size 1.1684 1.1684)
			(drill 0.762)
			(layers "*.Cu" "*.Mask")
			(remove_unused_layers no)
			(net "P12V")
			(clearance 0.0508)
			(thermal_gap 0.0508)
		)
		(pad "P19" thru_hole circle
			(at -2.70002 33.02)
			(size 1.1684 1.1684)
			(drill 0.762)
			(layers "*.Cu" "*.Mask")
			(remove_unused_layers no)
			(net "P12V")
			(clearance 0.0508)
			(thermal_gap 0.0508)
		)
		(pad "P20" thru_hole circle
			(at -2.70002 30.48)
			(size 1.1684 1.1684)
			(drill 0.762)
			(layers "*.Cu" "*.Mask")
			(remove_unused_layers no)
			(net "P12V")
			(clearance 0.0508)
			(thermal_gap 0.0508)
		)
		(pad "P21" thru_hole circle
			(at -2.70002 27.94)
			(size 1.1684 1.1684)
			(drill 0.762)
			(layers "*.Cu" "*.Mask")
			(remove_unused_layers no)
			(net "P12V")
			(clearance 0.0508)
			(thermal_gap 0.0508)
		)
		(pad "P22" thru_hole circle
			(at -2.70002 25.4)
			(size 1.1684 1.1684)
			(drill 0.762)
			(layers "*.Cu" "*.Mask")
			(remove_unused_layers no)
			(net "P12V")
			(clearance 0.0508)
			(thermal_gap 0.0508)
		)
		(pad "P23" thru_hole circle
			(at -2.70002 22.86)
			(size 1.1684 1.1684)
			(drill 0.762)
			(layers "*.Cu" "*.Mask")
			(remove_unused_layers no)
			(net "P12V")
			(clearance 0.0508)
			(thermal_gap 0.0508)
		)
		(pad "P24" thru_hole circle
			(at -2.70002 20.32)
			(size 1.1684 1.1684)
			(drill 0.762)
			(layers "*.Cu" "*.Mask")
			(remove_unused_layers no)
			(net "P12V")
			(clearance 0.0508)
			(thermal_gap 0.0508)
		)
		(pad "P25" thru_hole circle
			(at -2.70002 17.78)
			(size 1.1684 1.1684)
			(drill 0.762)
			(layers "*.Cu" "*.Mask")
			(remove_unused_layers no)
			(net "GND")
			(clearance 0.0508)
			(thermal_gap 0.0508)
		)
		(pad "P26" thru_hole circle
			(at -2.70002 15.24)
			(size 1.1684 1.1684)
			(drill 0.762)
			(layers "*.Cu" "*.Mask")
			(remove_unused_layers no)
			(net "GND")
			(clearance 0.0508)
			(thermal_gap 0.0508)
		)
		(pad "P27" thru_hole circle
			(at -2.70002 12.7)
			(size 1.1684 1.1684)
			(drill 0.762)
			(layers "*.Cu" "*.Mask")
			(remove_unused_layers no)
			(net "GND")
			(clearance 0.0508)
			(thermal_gap 0.0508)
		)
		(pad "P28" thru_hole circle
			(at -2.70002 10.16)
			(size 1.1684 1.1684)
			(drill 0.762)
			(layers "*.Cu" "*.Mask")
			(remove_unused_layers no)
			(net "GND")
			(clearance 0.0508)
			(thermal_gap 0.0508)
		)
		(pad "P29" thru_hole circle
			(at -2.70002 7.62)
			(size 1.1684 1.1684)
			(drill 0.762)
			(layers "*.Cu" "*.Mask")
			(remove_unused_layers no)
			(net "GND")
			(clearance 0.0508)
			(thermal_gap 0.0508)
		)
		(pad "P30" thru_hole circle
			(at -2.70002 5.08)
			(size 1.1684 1.1684)
			(drill 0.762)
			(layers "*.Cu" "*.Mask")
			(remove_unused_layers no)
			(net "GND")
			(clearance 0.0508)
			(thermal_gap 0.0508)
		)
		(pad "P31" thru_hole circle
			(at -2.70002 2.54)
			(size 1.1684 1.1684)
			(drill 0.762)
			(layers "*.Cu" "*.Mask")
			(remove_unused_layers no)
			(net "GND")
			(clearance 0.0508)
			(thermal_gap 0.0508)
		)
		(pad "P32" thru_hole circle
			(at -2.70002 0)
			(size 1.1684 1.1684)
			(drill 0.762)
			(layers "*.Cu" "*.Mask")
			(remove_unused_layers no)
			(net "GND")
			(clearance 0.0508)
			(thermal_gap 0.0508)
		)
		(pad "S1" thru_hole circle
			(at 0.55499 41.60012)
			(size 1.1684 1.1684)
			(drill 0.762)
			(layers "*.Cu" "*.Mask")
			(remove_unused_layers no)
			(net "T5_BLAD1_TXD")
			(clearance 0.0508)
			(thermal_gap 0.0508)
		)
		(pad "S2" thru_hole circle
			(at -0.71501 42.87012)
			(size 1.1684 1.1684)
			(drill 0.762)
			(layers "*.Cu" "*.Mask")
			(remove_unused_layers no)
			(net "T5_BLAD1_RXD")
			(clearance 0.0508)
			(thermal_gap 0.0508)
		)
		(pad "S3" thru_hole circle
			(at 0.55499 44.14012)
			(size 1.1684 1.1684)
			(drill 0.762)
			(layers "*.Cu" "*.Mask")
			(remove_unused_layers no)
			(net "T5_BLAD1_EN")
			(clearance 0.0508)
			(thermal_gap 0.0508)
		)
		(pad "S4" thru_hole circle
			(at -0.71501 45.41012)
			(size 1.1684 1.1684)
			(drill 0.762)
			(layers "*.Cu" "*.Mask")
			(remove_unused_layers no)
			(net "T5_BLAD2_EN")
			(clearance 0.0508)
			(thermal_gap 0.0508)
		)
		(pad "S5" thru_hole circle
			(at 0.55499 46.68012)
			(size 1.1684 1.1684)
			(drill 0.762)
			(layers "*.Cu" "*.Mask")
			(remove_unused_layers no)
			(net "T5_BLAD2_TXD")
			(clearance 0.0508)
			(thermal_gap 0.0508)
		)
		(pad "S6" thru_hole circle
			(at -0.71501 47.95012)
			(size 1.1684 1.1684)
			(drill 0.762)
			(layers "*.Cu" "*.Mask")
			(remove_unused_layers no)
			(net "T5_BLAD2_RXD")
			(clearance 0.0508)
			(thermal_gap 0.0508)
		)
		(pad "S7" thru_hole circle
			(at -3.25501 47.95012)
			(size 1.1684 1.1684)
			(drill 0.762)
			(layers "*.Cu" "*.Mask")
			(remove_unused_layers no)
			(net "T5_BLAD4_RXD")
			(clearance 0.0508)
			(thermal_gap 0.0508)
		)
		(pad "S8" thru_hole circle
			(at -1.98501 46.68012)
			(size 1.1684 1.1684)
			(drill 0.762)
			(layers "*.Cu" "*.Mask")
			(remove_unused_layers no)
			(net "T5_BLAD4_TXD")
			(clearance 0.0508)
			(thermal_gap 0.0508)
		)
		(pad "S9" thru_hole circle
			(at -3.25501 45.41012)
			(size 1.1684 1.1684)
			(drill 0.762)
			(layers "*.Cu" "*.Mask")
			(remove_unused_layers no)
			(net "T5_BLAD4_EN")
			(clearance 0.0508)
			(thermal_gap 0.0508)
		)
		(pad "S10" thru_hole circle
			(at -1.98501 44.14012)
			(size 1.1684 1.1684)
			(drill 0.762)
			(layers "*.Cu" "*.Mask")
			(remove_unused_layers no)
			(net "T5_BLAD3_EN")
			(clearance 0.0508)
			(thermal_gap 0.0508)
		)
		(pad "S11" thru_hole circle
			(at -3.25501 42.87012)
			(size 1.1684 1.1684)
			(drill 0.762)
			(layers "*.Cu" "*.Mask")
			(remove_unused_layers no)
			(net "T5_BLAD3_RXD")
			(clearance 0.0508)
			(thermal_gap 0.0508)
		)
		(pad "S12" thru_hole circle
			(at -1.98501 41.60012)
			(size 1.1684 1.1684)
			(drill 0.762)
			(layers "*.Cu" "*.Mask")
			(remove_unused_layers no)
			(net "T5_BLAD3_TXD")
			(clearance 0.0508)
			(thermal_gap 0.0508)
		)
	)
)
